FILE_TYPE = CONNECTIVITY;
{Allegro Design Entry HDL 17.2-2016 S081 (4005846) 1/11/2022}
"PAGE_NUMBER" = 191;
0"NC";
1"GND\g";
2"GND\g";
3"GND\g";
4"GND\g";
5"GND\g";
6"IND_SOC_P1_CPL0";
7"SW_PVDDCR_SOC_P1_SW3";
8"PVDDCR_SOC_P1\g";
9"GND\g";
10"GND\g";
11"PVDDCR_CPU0_P1_VCCS";
12"PVDDCR_SOC_P1_LSET3";
13"NC_PVDDCR_SOC_P1_DNC3";
14"PVDDCR_SOC_P1_TEMP1";
15"PVDDCR_SOC_P1_PWM3";
16"GND\g";
17"NC_PVDDCR_SOC_P1_GL1_3";
18"NC_PVDDCR_SOC_P1_GL2_3";
19"PVDDCR_SOC_P1_VOS3";
20"SW_PVDDCR_SOC_P1_SW3_RC";
21"PVDDCR_CPU0_P1_PVCC\g";
22"PVDDCR_SOC_P1_VCC3";
23"PVDDCR_SOC_P1_IMON3";
24"SW_P12V_STBY_PVDDCR_SOC_P1_FLT\g";
25"SW_PVDDCR_SOC_P1_BOOT3";
26"IND_SOC_P1_CPL3";
27"GND\g";
28"SW_PVDDCR_SOC_P1_PH3";
29"SW_PVDDCR_SOC_P1_BOOT3_RC";
%"UNIVERSAL_GND"
"1","(-5250,3425)","0","pure_quanta_power","I16";
;
CDS_LIB"pure_quanta_power"
HDL_POWER"GND";
"A"16;
%"Q_RES"
"1","(-3975,2950)","0","pure_quanta","I17";
;
LOCATION"PR216"
$SEC"1"
CDS_SEC"1"
WATTAGE"1/16W"
MATERIAL"CHIP"
TOLERANCE"5%"
VALUE"0"
PART_NUMBER"CS00002JB38"
PACK_TYPE"0402LF"
CDS_LIB"pure_quanta";
"B"
$PN"2"8;
"A"
$PN"1"19;
%"Q_RES"
"1","(-4450,4500)","0","pure_quanta","I18";
;
LOCATION"PR215"
$SEC"1"
CDS_SEC"1"
PACK_TYPE"0402LF"
TOLERANCE"1%"
MATERIAL"CHIP"
WATTAGE"1/16W"
VALUE"4.7"
PART_NUMBER"CS-4702FB19"
CDS_LIB"pure_quanta";
"B"
$PN"2"29;
"A"
$PN"1"25;
%"UNIVERSAL_GND"
"1","(-7650,3600)","0","pure_quanta_power","I2";
;
CDS_LIB"pure_quanta_power"
HDL_POWER"GND";
"A"1;
%"Q_CAP"
"1","(-4625,5025)","0","pure_quanta","I20";
;
LOCATION"PC349_3"
$SEC"1"
CDS_SEC"1"
MATERIAL"X6S"
TOLERANCE"10%"
VALUE"1UF"
PART_NUMBER"CH5104KEB02"
VOLTAGE"25V"
PACK_TYPE"C0402"
CDS_LIB"pure_quanta";
"B"
$PN"2"10;
"A"
$PN"1"24;
%"Q_CAP"
"1","(-4300,5025)","0","pure_quanta","I21";
;
LOCATION"PC350_3"
$SEC"1"
CDS_SEC"1"
MATERIAL"X6S"
TOLERANCE"10%"
VALUE"10UF"
PART_NUMBER"CH6104KEA00"
VOLTAGE"25V"
PACK_TYPE"C0805"
CDS_LIB"pure_quanta";
"B"
$PN"2"10;
"A"
$PN"1"24;
%"Q_CAP"
"1","(-3975,5025)","0","pure_quanta","I22";
;
LOCATION"PC351_3"
$SEC"1"
CDS_SEC"1"
MATERIAL"X6S"
TOLERANCE"10%"
VALUE"10UF"
VOLTAGE"25V"
PACK_TYPE"C0805"
PART_NUMBER"CH6104KEA00"
CDS_LIB"pure_quanta";
"B"
$PN"2"10;
"A"
$PN"1"24;
%"UNIVERSAL_GND"
"1","(-3300,4700)","0","pure_quanta_power","I23";
;
CDS_LIB"pure_quanta_power"
HDL_POWER"GND";
"A"10;
%"Q_CAP"
"1","(-1400,3975)","0","pure_quanta","I25";
;
LOCATION"PC354_3"
$SEC"1"
CDS_SEC"1"
MATERIAL"X6S"
TOLERANCE"20%"
VALUE"22UF"
PART_NUMBER"TMP_QCH622KMEA01"
VOLTAGE"4V"
PACK_TYPE"0805"
CDS_LIB"pure_quanta";
"B"
$PN"2"27;
"A"
$PN"1"8;
%"Q_CAP"
"1","(-3675,5025)","0","pure_quanta","I26";
;
LOCATION"PC352_3"
$SEC"1"
CDS_SEC"1"
MATERIAL"X6S"
VALUE"10UF"
PART_NUMBER"CH6104KEA00"
VOLTAGE"25V"
PACK_TYPE"C0805"
TOLERANCE"10%"
CDS_LIB"pure_quanta";
"B"
$PN"2"10;
"A"
$PN"1"24;
%"VCC_CORE"
"1","(-3300,5300)","0","pure_quanta_power","I27";
;
HDL_POWER"SW_P12V_STBY_PVDDCR_SOC_P1_FLT"
CDS_LIB"pure_quanta_power";
"A"24;
%"UNIVERSAL_GND"
"1","(-975,3625)","0","pure_quanta_power","I28";
;
CDS_LIB"pure_quanta_power"
HDL_POWER"GND";
"A"27;
%"Q_CAP"
"1","(-975,3975)","0","pure_quanta","I29";
;
LOCATION"PC355_3"
$SEC"1"
CDS_SEC"1"
MATERIAL"X6S"
TOLERANCE"20%"
VALUE"22UF"
PART_NUMBER"TMP_QCH622KMEA01"
VOLTAGE"4V"
PACK_TYPE"0805"
CDS_LIB"pure_quanta";
"B"
$PN"2"27;
"A"
$PN"1"8;
%"UNIVERSAL_GND"
"1","(-7300,3675)","0","pure_quanta_power","I3";
;
CDS_LIB"pure_quanta_power"
HDL_POWER"GND";
"A"2;
%"VCC_CORE"
"1","(-975,4300)","0","pure_quanta_power","I30";
;
HDL_POWER"PVDDCR_SOC_P1"
CDS_LIB"pure_quanta_power";
"A"8;
%"Q_INDUCTOR4P_14"
"1","(-2625,4025)","0","pure_quanta","I31";
;
LOCATION"PL38"
$SEC"1"
CDS_SEC"1"
PART_TYPE"SMLF"
MATERIAL"IND"
VALUE"150NH"
PART_NUMBER"CV+15^0TZ04"
CDS_LIB"pure_quanta"
NEEDS_NO_SIZE"TRUE";
"1"
$PN"1"7;
"4"
$PN"4"8;
"3"
$PN"3"26;
"2"
$PN"2"6;
%"Q_CAP"
"1","(-3475,4375)","0","pure_quanta","I32";
;
LOCATION"PC353"
$SEC"1"
CDS_SEC"1"
MATERIAL"X7R"
TOLERANCE"10%"
VALUE"0.22UF"
PART_NUMBER"CH4223K1B00"
VOLTAGE"16V"
PACK_TYPE"0402"
CDS_LIB"pure_quanta";
"B"
$PN"2"28;
"A"
$PN"1"29;
%"ISL99390FRZTR5935"
"1","(-5825,4150)","0","pure_quanta","I34";
;
LOCATION"PU32"
$SEC"1"
CDS_SEC"1"
PART_TYPE"SMLF"
MATERIAL"IC"
VALUE"ISL99390FRZ-TR5935"
PART_NUMBER"AL099390004"
CDS_LIB"pure_quanta"
CDS_LMAN_SYM_OUTLINE"-300,700,250,-650"
NEEDS_NO_SIZE"TRUE";
"PGND2"
$PN"7_9-20_24"16;
"GL2"
$PN"41"18;
"GL1"
$PN"6"17;
"DNC"
$PN"31"13;
"EN"
$PN"35"22;
"PGND3"
$PN"40"16;
"VOS"
$PN"1"19;
"VIN2"
$PN"30"24;
"PGND1"
$PN"5"16;
"SW"
$PN"10_19"7;
"LSET"
$PN"37"12;
"IOUT"
$PN"38"23;
"TOUT_FLT"
$PN"36"14;
"PVCC"
$PN"4"21;
"PHASE"
$PN"32"28;
"VIN1"
$PN"25_29"24;
"BOOT"
$PN"33"25;
"AGND"
$PN"2"16;
"VCC"
$PN"3"22;
"REFIN"
$PN"39"11;
"PWM"
$PN"34"15;
%"Q_CAP"
"1","(-5025,5025)","0","pure_quanta","I37";
;
LOCATION"PC348_3"
$SEC"1"
CDS_SEC"1"
MATERIAL"X7R"
TOLERANCE"10%"
VALUE"0.1UF"
PART_NUMBER"CH4104K1B00"
VOLTAGE"25V"
PACK_TYPE"0402"
CDS_LIB"pure_quanta";
"B"
$PN"2"10;
"A"
$PN"1"24;
%"Q_CAP"
"1","(-7325,4500)","0","pure_quanta","I38";
;
LOCATION"PC346"
$SEC"1"
CDS_SEC"1"
MATERIAL"X6S"
TOLERANCE"10%"
VALUE"2.2UF"
PART_NUMBER"CH5222KEB01"
VOLTAGE"10V"
PACK_TYPE"C0402"
CDS_LIB"pure_quanta";
"B"
$PN"2"3;
"A"
$PN"1"22;
%"UNIVERSAL_GND"
"1","(-7325,4300)","0","pure_quanta_power","I39";
;
CDS_LIB"pure_quanta_power"
HDL_POWER"GND";
"A"3;
%"UNIVERSAL_GND"
"1","(-6975,4800)","0","pure_quanta_power","I40";
;
CDS_LIB"pure_quanta_power"
HDL_POWER"GND";
"A"4;
%"Q_RES"
"2","(-7325,5050)","0","pure_quanta","I41";
;
LOCATION"PR213"
$SEC"1"
CDS_SEC"1"
WATTAGE"1/16W"
MATERIAL"CHIP"
TOLERANCE"1%"
VALUE"2.2"
PART_NUMBER"CS-2202FB00"
PACK_TYPE"0402LF"
CDS_LIB"pure_quanta";
"A"
$PN"1"21;
"B"
$PN"2"22;
%"Q_CAP"
"1","(-6975,5075)","0","pure_quanta","I42";
;
LOCATION"PC347_SOP1_3"
$SEC"1"
CDS_SEC"1"
MATERIAL"X6S"
TOLERANCE"10%"
VALUE"2.2UF"
PART_NUMBER"CH5222KEB01"
VOLTAGE"10V"
PACK_TYPE"C0402"
CDS_LIB"pure_quanta";
"B"
$PN"2"4;
"A"
$PN"1"21;
%"VCC_CORE"
"1","(-7325,5450)","0","pure_quanta_power","I43";
;
HDL_POWER"PVDDCR_CPU0_P1_PVCC"
CDS_LIB"pure_quanta_power";
"A"21;
%"UNIVERSAL_GND"
"1","(-4425,3200)","0","pure_quanta_power","I45";
;
CDS_LIB"pure_quanta_power"
HDL_POWER"GND";
"A"5;
%"Q_RES"
"2","(-4425,3425)","0","pure_quanta","I46";
;
LOCATION"PR511"
$SEC"1"
CDS_SEC"1"
WATTAGE"1/8W"
MATERIAL"EMPTY"
TOLERANCE"1%"
VALUE"1.5"
PART_NUMBER"CS-1504FB00"
PACK_TYPE"0402LF"
CDS_LIB"pure_quanta";
"A"
$PN"1"20;
"B"
$PN"2"5;
%"Q_CAP"
"1","(-4425,3950)","0","pure_quanta","I47";
;
LOCATION"PC195"
$SEC"1"
CDS_SEC"1"
MATERIAL"EMPTY"
TOLERANCE"10%"
VALUE"560PF"
VOLTAGE"50V"
PACK_TYPE"C0402"
PART_NUMBER"CH1566K1B09"
CDS_LIB"pure_quanta";
"B"
$PN"2"20;
"A"
$PN"1"7;
%"Q_CAP"
"1","(-3300,5025)","0","pure_quanta","I48";
;
LOCATION"PC353_3"
$SEC"1"
CDS_SEC"1"
MATERIAL"X6S"
TOLERANCE"10%"
VALUE"10UF"
PART_NUMBER"CH6104KEA00"
VOLTAGE"25V"
PACK_TYPE"C0805"
CDS_LIB"pure_quanta";
"B"
$PN"2"10;
"A"
$PN"1"24;
%"Q_INDUCTOR"
"1","(-3625,3925)","0","pure_quanta","I52";
;
LOCATION"PL34"
$SEC"1"
CDS_SEC"1"
PART_NUMBER"CV+22Y0EZ00"
VALUE"0.22UH/33A"
PACK_TYPE"SMLF"
MATERIAL"IND"
NEEDS_NO_SIZE"TRUE"
CDS_LIB"pure_quanta";
"1"
$PN"1"9;
"2"
$PN"2"6;
%"UNIVERSAL_GND"
"1","(-3800,3800)","0","pure_quanta_power","I53";
;
CDS_LIB"pure_quanta_power"
HDL_POWER"GND";
"A"9;
%"Q_CAP"
"1","(-7650,3875)","0","pure_quanta","I6";
;
LOCATION"PC345_9"
$SEC"1"
CDS_SEC"1"
MATERIAL"X7R"
TOLERANCE"10%"
VALUE"0.1UF"
PART_NUMBER"CH4104K1B00"
VOLTAGE"25V"
PACK_TYPE"0402"
CDS_LIB"pure_quanta";
"B"
$PN"2"1;
"A"
$PN"1"11;
%"Q_RES"
"1","(-6975,3850)","0","pure_quanta","I7";
;
LOCATION"PR214"
$SEC"1"
CDS_SEC"1"
WATTAGE"1/16W"
MATERIAL"EMPTY"
TOLERANCE"1%"
VALUE"8.87K"
PART_NUMBER"CS28872FB01"
PACK_TYPE"0402LF"
CDS_LIB"pure_quanta";
"B"
$PN"2"12;
"A"
$PN"1"2;
END.
